# BASEBOARD_FAB2 (Tioga Pass) — schematic parts with pin connectivity, parts 4568–4636 of 4751; source: Cadence DE-HDL packaged netlist (pstxprt.dat, pstxnet.dat, pstchip.dat)

T1D2  TEST-PAD-12P-1-GP-U  pkg DISCRET-GB1  page 257
  1  DP  UNSPEC  = L1_85OHM_5INCH_DN
  2  DN  UNSPEC  = L1_85OHM_5INCH_DP
  3  GND(0)  POWER  = GND
  4  GND(1)  POWER  = GND
  5  GND(2)  POWER  = GND
  6  GND(3)  POWER  = GND
  7  GND(4)  POWER  = GND
  8  GND(5)  POWER  = GND
  9  GND(6)  POWER  = GND
  10  GND(7)  POWER  = GND
  11  GND(8)  POWER  = GND
  12  GND(9)  POWER  = GND

T1D3  TEST-PAD-12P-1-GP-U  pkg DISCRET-GB1  page 257
  1  DP  UNSPEC  = L3_85OHM_5INCH_DP
  2  DN  UNSPEC  = L3_85OHM_5INCH_DN
  3  GND(0)  POWER  = GND
  4  GND(1)  POWER  = GND
  5  GND(2)  POWER  = GND
  6  GND(3)  POWER  = GND
  7  GND(4)  POWER  = GND
  8  GND(5)  POWER  = GND
  9  GND(6)  POWER  = GND
  10  GND(7)  POWER  = GND
  11  GND(8)  POWER  = GND
  12  GND(9)  POWER  = GND

T1D4  TEST-PAD-12P-1-GP-U  pkg DISCRET-GB1  page 257
  1  DP  UNSPEC  = L3_85OHM_5INCH_DN
  2  DN  UNSPEC  = L3_85OHM_5INCH_DP
  3  GND(0)  POWER  = GND
  4  GND(1)  POWER  = GND
  5  GND(2)  POWER  = GND
  6  GND(3)  POWER  = GND
  7  GND(4)  POWER  = GND
  8  GND(5)  POWER  = GND
  9  GND(6)  POWER  = GND
  10  GND(7)  POWER  = GND
  11  GND(8)  POWER  = GND
  12  GND(9)  POWER  = GND

T1D5  TEST-PAD-12P-1-GP-U  pkg DISCRET-GB1  page 257
  1  DP  UNSPEC  = L5_85OHM_5INCH_DP
  2  DN  UNSPEC  = L5_85OHM_5INCH_DN
  3  GND(0)  POWER  = GND
  4  GND(1)  POWER  = GND
  5  GND(2)  POWER  = GND
  6  GND(3)  POWER  = GND
  7  GND(4)  POWER  = GND
  8  GND(5)  POWER  = GND
  9  GND(6)  POWER  = GND
  10  GND(7)  POWER  = GND
  11  GND(8)  POWER  = GND
  12  GND(9)  POWER  = GND

T1D6  TEST-PAD-12P-1-GP-U  pkg DISCRET-GB1  page 257
  1  DP  UNSPEC  = L5_85OHM_5INCH_DN
  2  DN  UNSPEC  = L5_85OHM_5INCH_DP
  3  GND(0)  POWER  = GND
  4  GND(1)  POWER  = GND
  5  GND(2)  POWER  = GND
  6  GND(3)  POWER  = GND
  7  GND(4)  POWER  = GND
  8  GND(5)  POWER  = GND
  9  GND(6)  POWER  = GND
  10  GND(7)  POWER  = GND
  11  GND(8)  POWER  = GND
  12  GND(9)  POWER  = GND

T1D7  TEST-PAD-12P-1-GP-U  pkg DISCRET-GB1  page 257
  1  DP  UNSPEC  = L10_85OHM_5INCH_DP
  2  DN  UNSPEC  = L10_85OHM_5INCH_DN
  3  GND(0)  POWER  = GND
  4  GND(1)  POWER  = GND
  5  GND(2)  POWER  = GND
  6  GND(3)  POWER  = GND
  7  GND(4)  POWER  = GND
  8  GND(5)  POWER  = GND
  9  GND(6)  POWER  = GND
  10  GND(7)  POWER  = GND
  11  GND(8)  POWER  = GND
  12  GND(9)  POWER  = GND

T1D8  TEST-PAD-12P-1-GP-U  pkg DISCRET-GB1  page 257
  1  DP  UNSPEC  = L10_85OHM_5INCH_DN
  2  DN  UNSPEC  = L10_85OHM_5INCH_DP
  3  GND(0)  POWER  = GND
  4  GND(1)  POWER  = GND
  5  GND(2)  POWER  = GND
  6  GND(3)  POWER  = GND
  7  GND(4)  POWER  = GND
  8  GND(5)  POWER  = GND
  9  GND(6)  POWER  = GND
  10  GND(7)  POWER  = GND
  11  GND(8)  POWER  = GND
  12  GND(9)  POWER  = GND

T1D9  TEST-PAD-12P-1-GP-U  pkg DISCRET-GB1  page 257
  1  DP  UNSPEC  = L12_85OHM_5INCH_DP
  2  DN  UNSPEC  = L12_85OHM_5INCH_DN
  3  GND(0)  POWER  = GND
  4  GND(1)  POWER  = GND
  5  GND(2)  POWER  = GND
  6  GND(3)  POWER  = GND
  7  GND(4)  POWER  = GND
  8  GND(5)  POWER  = GND
  9  GND(6)  POWER  = GND
  10  GND(7)  POWER  = GND
  11  GND(8)  POWER  = GND
  12  GND(9)  POWER  = GND

T1D10  TEST-PAD-12P-1-GP-U  pkg DISCRET-GB1  page 257
  1  DP  UNSPEC  = L12_85OHM_5INCH_DN
  2  DN  UNSPEC  = L12_85OHM_5INCH_DP
  3  GND(0)  POWER  = GND
  4  GND(1)  POWER  = GND
  5  GND(2)  POWER  = GND
  6  GND(3)  POWER  = GND
  7  GND(4)  POWER  = GND
  8  GND(5)  POWER  = GND
  9  GND(6)  POWER  = GND
  10  GND(7)  POWER  = GND
  11  GND(8)  POWER  = GND
  12  GND(9)  POWER  = GND

T1D11  TEST-PAD-12P-1-GP-U  pkg DISCRET-GB1  page 257
  1  DP  UNSPEC  = L14_85OHM_5INCH_DP
  2  DN  UNSPEC  = L14_85OHM_5INCH_DN
  3  GND(0)  POWER  = GND
  4  GND(1)  POWER  = GND
  5  GND(2)  POWER  = GND
  6  GND(3)  POWER  = GND
  7  GND(4)  POWER  = GND
  8  GND(5)  POWER  = GND
  9  GND(6)  POWER  = GND
  10  GND(7)  POWER  = GND
  11  GND(8)  POWER  = GND
  12  GND(9)  POWER  = GND

T1D12  TEST-PAD-12P-1-GP-U  pkg DISCRET-GB1  page 257
  1  DP  UNSPEC  = L14_85OHM_5INCH_DN
  2  DN  UNSPEC  = L14_85OHM_5INCH_DP
  3  GND(0)  POWER  = GND
  4  GND(1)  POWER  = GND
  5  GND(2)  POWER  = GND
  6  GND(3)  POWER  = GND
  7  GND(4)  POWER  = GND
  8  GND(5)  POWER  = GND
  9  GND(6)  POWER  = GND
  10  GND(7)  POWER  = GND
  11  GND(8)  POWER  = GND
  12  GND(9)  POWER  = GND

T1D13  TEST-PAD-12P-1-GP-U  pkg DISCRET-GB1  page 258
  1  DP  UNSPEC  = L1_85OHM_10INCH_DP
  2  DN  UNSPEC  = L1_85OHM_10INCH_DN
  3  GND(0)  POWER  = GND
  4  GND(1)  POWER  = GND
  5  GND(2)  POWER  = GND
  6  GND(3)  POWER  = GND
  7  GND(4)  POWER  = GND
  8  GND(5)  POWER  = GND
  9  GND(6)  POWER  = GND
  10  GND(7)  POWER  = GND
  11  GND(8)  POWER  = GND
  12  GND(9)  POWER  = GND

T1D14  TEST-PAD-12P-1-GP-U  pkg DISCRET-GB1  page 258
  1  DP  UNSPEC  = L1_85OHM_10INCH_DN
  2  DN  UNSPEC  = L1_85OHM_10INCH_DP
  3  GND(0)  POWER  = GND
  4  GND(1)  POWER  = GND
  5  GND(2)  POWER  = GND
  6  GND(3)  POWER  = GND
  7  GND(4)  POWER  = GND
  8  GND(5)  POWER  = GND
  9  GND(6)  POWER  = GND
  10  GND(7)  POWER  = GND
  11  GND(8)  POWER  = GND
  12  GND(9)  POWER  = GND

T1D15  TEST-PAD-12P-1-GP-U  pkg DISCRET-GB1  page 258
  1  DP  UNSPEC  = L3_85OHM_10INCH_DP
  2  DN  UNSPEC  = L3_85OHM_10INCH_DN
  3  GND(0)  POWER  = GND
  4  GND(1)  POWER  = GND
  5  GND(2)  POWER  = GND
  6  GND(3)  POWER  = GND
  7  GND(4)  POWER  = GND
  8  GND(5)  POWER  = GND
  9  GND(6)  POWER  = GND
  10  GND(7)  POWER  = GND
  11  GND(8)  POWER  = GND
  12  GND(9)  POWER  = GND

T1D16  TEST-PAD-12P-1-GP-U  pkg DISCRET-GB1  page 258
  1  DP  UNSPEC  = L3_85OHM_10INCH_DN
  2  DN  UNSPEC  = L3_85OHM_10INCH_DP
  3  GND(0)  POWER  = GND
  4  GND(1)  POWER  = GND
  5  GND(2)  POWER  = GND
  6  GND(3)  POWER  = GND
  7  GND(4)  POWER  = GND
  8  GND(5)  POWER  = GND
  9  GND(6)  POWER  = GND
  10  GND(7)  POWER  = GND
  11  GND(8)  POWER  = GND
  12  GND(9)  POWER  = GND

T1D17  TEST-PAD-12P-1-GP-U  pkg DISCRET-GB1  page 258
  1  DP  UNSPEC  = L5_85OHM_10INCH_DP
  2  DN  UNSPEC  = L5_85OHM_10INCH_DN
  3  GND(0)  POWER  = GND
  4  GND(1)  POWER  = GND
  5  GND(2)  POWER  = GND
  6  GND(3)  POWER  = GND
  7  GND(4)  POWER  = GND
  8  GND(5)  POWER  = GND
  9  GND(6)  POWER  = GND
  10  GND(7)  POWER  = GND
  11  GND(8)  POWER  = GND
  12  GND(9)  POWER  = GND

T1D18  TEST-PAD-12P-1-GP-U  pkg DISCRET-GB1  page 258
  1  DP  UNSPEC  = L5_85OHM_10INCH_DN
  2  DN  UNSPEC  = L5_85OHM_10INCH_DP
  3  GND(0)  POWER  = GND
  4  GND(1)  POWER  = GND
  5  GND(2)  POWER  = GND
  6  GND(3)  POWER  = GND
  7  GND(4)  POWER  = GND
  8  GND(5)  POWER  = GND
  9  GND(6)  POWER  = GND
  10  GND(7)  POWER  = GND
  11  GND(8)  POWER  = GND
  12  GND(9)  POWER  = GND

T1D19  TEST-PAD-12P-1-GP-U  pkg DISCRET-GB1  page 258
  1  DP  UNSPEC  = L10_85OHM_10INCH_DP
  2  DN  UNSPEC  = L10_85OHM_10INCH_DN
  3  GND(0)  POWER  = GND
  4  GND(1)  POWER  = GND
  5  GND(2)  POWER  = GND
  6  GND(3)  POWER  = GND
  7  GND(4)  POWER  = GND
  8  GND(5)  POWER  = GND
  9  GND(6)  POWER  = GND
  10  GND(7)  POWER  = GND
  11  GND(8)  POWER  = GND
  12  GND(9)  POWER  = GND

T1D20  TEST-PAD-12P-1-GP-U  pkg DISCRET-GB1  page 258
  1  DP  UNSPEC  = L10_85OHM_10INCH_DN
  2  DN  UNSPEC  = L10_85OHM_10INCH_DP
  3  GND(0)  POWER  = GND
  4  GND(1)  POWER  = GND
  5  GND(2)  POWER  = GND
  6  GND(3)  POWER  = GND
  7  GND(4)  POWER  = GND
  8  GND(5)  POWER  = GND
  9  GND(6)  POWER  = GND
  10  GND(7)  POWER  = GND
  11  GND(8)  POWER  = GND
  12  GND(9)  POWER  = GND

T1D21  TEST-PAD-12P-1-GP-U  pkg DISCRET-GB1  page 258
  1  DP  UNSPEC  = L12_85OHM_10INCH_DP
  2  DN  UNSPEC  = L12_85OHM_10INCH_DN
  3  GND(0)  POWER  = GND
  4  GND(1)  POWER  = GND
  5  GND(2)  POWER  = GND
  6  GND(3)  POWER  = GND
  7  GND(4)  POWER  = GND
  8  GND(5)  POWER  = GND
  9  GND(6)  POWER  = GND
  10  GND(7)  POWER  = GND
  11  GND(8)  POWER  = GND
  12  GND(9)  POWER  = GND

T1D22  TEST-PAD-12P-1-GP-U  pkg DISCRET-GB1  page 258
  1  DP  UNSPEC  = L12_85OHM_10INCH_DN
  2  DN  UNSPEC  = L12_85OHM_10INCH_DP
  3  GND(0)  POWER  = GND
  4  GND(1)  POWER  = GND
  5  GND(2)  POWER  = GND
  6  GND(3)  POWER  = GND
  7  GND(4)  POWER  = GND
  8  GND(5)  POWER  = GND
  9  GND(6)  POWER  = GND
  10  GND(7)  POWER  = GND
  11  GND(8)  POWER  = GND
  12  GND(9)  POWER  = GND

T1D23  TEST-PAD-12P-1-GP-U  pkg DISCRET-GB1  page 258
  1  DP  UNSPEC  = L14_85OHM_10INCH_DP
  2  DN  UNSPEC  = L14_85OHM_10INCH_DN
  3  GND(0)  POWER  = GND
  4  GND(1)  POWER  = GND
  5  GND(2)  POWER  = GND
  6  GND(3)  POWER  = GND
  7  GND(4)  POWER  = GND
  8  GND(5)  POWER  = GND
  9  GND(6)  POWER  = GND
  10  GND(7)  POWER  = GND
  11  GND(8)  POWER  = GND
  12  GND(9)  POWER  = GND

T1D24  TEST-PAD-12P-1-GP-U  pkg DISCRET-GB1  page 258
  1  DP  UNSPEC  = L14_85OHM_10INCH_DN
  2  DN  UNSPEC  = L14_85OHM_10INCH_DP
  3  GND(0)  POWER  = GND
  4  GND(1)  POWER  = GND
  5  GND(2)  POWER  = GND
  6  GND(3)  POWER  = GND
  7  GND(4)  POWER  = GND
  8  GND(5)  POWER  = GND
  9  GND(6)  POWER  = GND
  10  GND(7)  POWER  = GND
  11  GND(8)  POWER  = GND
  12  GND(9)  POWER  = GND

T1P1  TPAD-DIFF-4P-GP  pkg DISCRET-GB3  page 256
  1  \1\  UNSPEC  = L1_85OHM_6INCH_DP
  2  \2\  UNSPEC  = L1_85OHM_6INCH_DN
  GND1  GND1  POWER  = GND
  GND2  GND2  POWER  = GND

T1P2  TPAD-DIFF-4P-GP  pkg DISCRET-GB3  page 256
  1  \1\  UNSPEC  = L3_85OHM_6INCH_DP
  2  \2\  UNSPEC  = L3_85OHM_6INCH_DN
  GND1  GND1  POWER  = GND
  GND2  GND2  POWER  = GND

T1P3  TPAD-DIFF-4P-GP  pkg DISCRET-GB3  page 256
  1  \1\  UNSPEC  = L5_85OHM_6INCH_DP
  2  \2\  UNSPEC  = L5_85OHM_6INCH_DN
  GND1  GND1  POWER  = GND
  GND2  GND2  POWER  = GND

T1P4  TPAD-DIFF-4P-GP  pkg DISCRET-GB3  page 256
  1  \1\  UNSPEC  = L10_85OHM_6INCH_DP
  2  \2\  UNSPEC  = L10_85OHM_6INCH_DN
  GND1  GND1  POWER  = GND
  GND2  GND2  POWER  = GND

T1P5  TPAD-DIFF-4P-GP  pkg DISCRET-GB3  page 256
  1  \1\  UNSPEC  = L12_85OHM_6INCH_DP
  2  \2\  UNSPEC  = L12_85OHM_6INCH_DN
  GND1  GND1  POWER  = GND
  GND2  GND2  POWER  = GND

T1P6  TPAD-DIFF-4P-GP  pkg DISCRET-GB3  page 256
  1  \1\  UNSPEC  = L14_85OHM_6INCH_DP
  2  \2\  UNSPEC  = L14_85OHM_6INCH_DN
  GND1  GND1  POWER  = GND
  GND2  GND2  POWER  = GND

T1P7  TPAD-DIFF-4P-GP  pkg DISCRET-GB3  page 256
  1  \1\  UNSPEC  = L1_73OHM_6INCH_DP
  2  \2\  UNSPEC  = L1_73OHM_6INCH_DN
  GND1  GND1  POWER  = GND
  GND2  GND2  POWER  = GND

T1P8  TPAD-DIFF-4P-GP  pkg DISCRET-GB3  page 256
  1  \1\  UNSPEC  = L3_73OHM_6INCH_DP
  2  \2\  UNSPEC  = L3_73OHM_6INCH_DN
  GND1  GND1  POWER  = GND
  GND2  GND2  POWER  = GND

T1P9  TPAD-DIFF-4P-GP  pkg DISCRET-GB3  page 256
  1  \1\  UNSPEC  = L5_73OHM_6INCH_DP
  2  \2\  UNSPEC  = L5_73OHM_6INCH_DN
  GND1  GND1  POWER  = GND
  GND2  GND2  POWER  = GND

T1P10  TPAD-DIFF-4P-GP  pkg DISCRET-GB3  page 256
  1  \1\  UNSPEC  = L10_73OHM_6INCH_DP
  2  \2\  UNSPEC  = L10_73OHM_6INCH_DN
  GND1  GND1  POWER  = GND
  GND2  GND2  POWER  = GND

T1P11  TPAD-DIFF-4P-GP  pkg DISCRET-GB3  page 256
  1  \1\  UNSPEC  = L12_73OHM_6INCH_DP
  2  \2\  UNSPEC  = L12_73OHM_6INCH_DN
  GND1  GND1  POWER  = GND
  GND2  GND2  POWER  = GND

T1P12  TPAD-DIFF-4P-GP  pkg DISCRET-GB3  page 256
  1  \1\  UNSPEC  = L14_73OHM_6INCH_DP
  2  \2\  UNSPEC  = L14_73OHM_6INCH_DN
  GND1  GND1  POWER  = GND
  GND2  GND2  POWER  = GND

T1P14  TPAD-DIFF-4P-GP  pkg DISCRET-GB3  page 256
  1  \1\  UNSPEC  = L1_95OHM_6INCH_DP
  2  \2\  UNSPEC  = L1_95OHM_6INCH_DN
  GND1  GND1  POWER  = GND
  GND2  GND2  POWER  = GND

T1P17  TPAD-DIFF-4P-GP  pkg DISCRET-GB3  page 256
  1  \1\  UNSPEC  = L12_95OHM_6INCH_DP
  2  \2\  UNSPEC  = L12_95OHM_6INCH_DN
  GND1  GND1  POWER  = GND
  GND2  GND2  POWER  = GND

T1P19  TPAD-DIFF-4P-GP  pkg DISCRET-GB3  page 256
  1  \1\  UNSPEC  = L1_100OHM_6INCH_DP
  2  \2\  UNSPEC  = L1_100OHM_6INCH_DN
  GND1  GND1  POWER  = GND
  GND2  GND2  POWER  = GND

T1P22  TPAD-DIFF-4P-GP  pkg DISCRET-GB3  page 256
  1  \1\  UNSPEC  = L10_100OHM_6INCH_DP
  2  \2\  UNSPEC  = L10_100OHM_6INCH_DN
  GND1  GND1  POWER  = GND
  GND2  GND2  POWER  = GND

T1P23  TPAD-DIFF-4P-GP  pkg DISCRET-GB3  page 256
  1  \1\  UNSPEC  = L12_100OHM_6INCH_DP
  2  \2\  UNSPEC  = L12_100OHM_6INCH_DN
  GND1  GND1  POWER  = GND
  GND2  GND2  POWER  = GND

T1P24  TPAD-DIFF-4P-GP  pkg DISCRET-GB3  page 256
  1  \1\  UNSPEC  = L14_100OHM_6INCH_DP
  2  \2\  UNSPEC  = L14_100OHM_6INCH_DN
  GND1  GND1  POWER  = GND
  GND2  GND2  POWER  = GND

T1P25  TPAD-SE-2P-GP  pkg DISCRET-GA1  page 256 : 1 = L1_40OHM_6INCH ; GND1 = GND
T1P26  TPAD-SE-2P-GP  pkg DISCRET-GA1  page 256 : 1 = L3_40OHM_6INCH ; GND1 = GND
T1P27  TPAD-SE-2P-GP  pkg DISCRET-GA1  page 256 : 1 = L5_40OHM_6INCH ; GND1 = GND
T1P28  TPAD-SE-2P-GP  pkg DISCRET-GA1  page 256 : 1 = L10_40OHM_6INCH ; GND1 = GND
T1P29  TPAD-SE-2P-GP  pkg DISCRET-GA1  page 256 : 1 = L12_40OHM_6INCH ; GND1 = GND
T1P30  TPAD-SE-2P-GP  pkg DISCRET-GA1  page 256 : 1 = L14_40OHM_6INCH ; GND1 = GND
T1P31  TPAD-SE-2P-GP  pkg DISCRET-GA1  page 256 : 1 = L1_50OHM_6INCH ; GND1 = GND
T1P32  TPAD-SE-2P-GP  pkg DISCRET-GA1  page 256 : 1 = L3_50OHM_6INCH ; GND1 = GND
T1P33  TPAD-SE-2P-GP  pkg DISCRET-GA1  page 256 : 1 = L5_50OHM_6INCH ; GND1 = GND
T1P34  TPAD-SE-2P-GP  pkg DISCRET-GA1  page 256 : 1 = L10_50OHM_6INCH ; GND1 = GND
T1P35  TPAD-SE-2P-GP  pkg DISCRET-GA1  page 256 : 1 = L12_50OHM_6INCH ; GND1 = GND
T1P36  TPAD-SE-2P-GP  pkg DISCRET-GA1  page 256 : 1 = L14_50OHM_6INCH ; GND1 = GND
TH1A1  MTG_KEYHOLE  EMPTY  pkg TH  page 195 : 1 = GND
TH4A1  MTG_KEYHOLE  EMPTY  pkg TH  page 195 : 1 = GND
TH4G1  MTG_KEYHOLE  EMPTY  pkg TH  page 195 : 1 = GND
TH7A1  MTG_KEYHOLE  EMPTY  pkg TH  page 195 : 1 = GND
TH7G1  MTG_KEYHOLE  EMPTY  pkg TH  page 195 : 1 = GND
TH9A1  MTG_KEYHOLE  EMPTY  pkg TH  page 195 : 1 = GND
TH9G1  MTG_KEYHOLE  EMPTY  pkg TH  page 195 : 1 = GND

U1B2  TCA9517DGKR-GP  pkg DISCRET-G8  page 163
  1  VCCA  POWER  = PVCCIO_CPU1
  2  SCLA  UNSPEC  = SMB_CPU1_PE_HP_GTL_R_SCL
  3  SDAA  UNSPEC  = SMB_CPU1_PE_HP_GTL_R_SDA
  4  GND  POWER  = GND
  5  EN  UNSPEC  = TP_SMB_PEHPCPU1_EN
  6  SDAB  UNSPEC  = SMB_PEHPCPU1_STBY_LVC3_R_SDA
  7  SCLB  UNSPEC  = SMB_PEHPCPU1_STBY_LVC3_R_SCL
  8  VCCB  POWER  = P3V3_STBY

U1D1  TTL1G126_A  74HC1G126 IC  pkg SOT  page 200
  1  OE  IN  = FM_OC_DETECT_EN
  2  A  IN  = IRQ_OC_DETECT_N
  4  Y  OUT  = FM_OC_DETECT_N

U1D2  TPS3700  IC  pkg SM  page 200
  1  OUTB  OUT  = IRQ_OC_DETECT_N
  2  VDD  POWER  = P12V_STBY
  3  INBN  BI  = A_HSC_HIGH
  4  INAP  BI  = A_HSC_LOW
  5  GND  GROUND  = GND
  6  OUTA  OUT  = A_HSC_LOW_GATE

U1E1  TMP421  IC  pkg TSSOP  page 167
  1  DXP  IN  = ISENSE_TMP421_2_DXP
  2  DXN  IN  = ISENSE_TMP421_2_DXN
  3  A(1)  IN  = PD_TMP421_2_A1
  4  A(0)  IN  = PU_TMP421_2_A0
  5  GND  GROUND  = GND
  6  SDA  BI  = SMB_SENSOR_TMP421_2_SDA
  7  SCL  BI  = SMB_SENSOR_TMP421_2_SCL
  8  VP  POWER  = P3V3_STBY

U1E2  TTL1G08  NC7SZ08 IC  pkg SOTLF  page 161
  1  A(0)  IN  = FM_CTNR_PS_ON
  2  B(0)  IN  = FM_DISABLE_FAN_N
  4  Y(0)  OUT  = FM_ENABLE_FAN_POWER

U1L1  TTL3126  74CBTLV3126 IC  pkg QFNLF  page 112
  1  OE(3)  = PWRGD_PVCCIN_CPU0
  2  A(3)  = XDP_TRST_N
  3  B(3)  = XDP_CPU_TRST_N
  4  OE(2)  = PWRGD_PVCCIN_CPU0
  5  A(2)  = XDP_TMS
  6  B(2)  = XDP_CPU_TMS
  8  B(1)  = XDP_CPU_TDO
  9  A(1)  = XDP_TDO
  10  OE(1)  = PWRGD_PVCCIN_CPU0
  11  B(0)  BI  = XDP_CPU_TDI
  12  A(0)  BI  = XDP_TDI
  13  OE(0)  IN  = PWRGD_PVCCIN_CPU0

U1L2  TTL1G86  74AHCT1G86 IC  pkg SOTLF  page 175
  1  A  IN  = PWRGD_P3V3_R
  2  B  IN  = FP_PWR_ID_LED_N
  4  Y  OUT  = FP_ID_LED_P5V_STBY_N

U1L3  ADM809  IC  pkg SMLF  page 196 : 2 = PWRGD_P3V3_R1 ; 3 = P3V3
U1L4  TTL1G07_A  74LVC1G07 IC  pkg SOP  page 111 : 2 = XDP_RST_CO_N ; 4 = FM_DEBUG_RST_BTN_R1_N
